# T6G (Grand Teton) — schematic netlist excerpt (pin names and nets, part order shuffled) for the footprints in the layout excerpt that follows; sources: Cadence DE-HDL packaged netlist, KiCad conversion of 04192023_DAF0TMB3IC0_F0TG_MB_C_brd_V02_OCP.brd

R755  Q_RES  4.7K 5% EMPTY  pkg 0201LF  page 331 : A = P1V8_CPU1_RT_1D ; B = RT_CPU1_P1_SCAN_MODE
R3113  Q_RES  33.2 1% CHIP  pkg 0402LF  page 240 : A = SMB_FAN_3V3AUX_SCL ; B = SMB_FAN_3V3AUX_R_SCL
R2419  Q_RES  33.2 1% CHIP  pkg 0402LF  page 150 : A = SMB_CPU0_CPU1_APML_SCL ; B = SMB_CPU0_CPU1_APML_SCL_R

(kicad_pcb
	(version 20260206)
	(generator "pcbnew")
	(generator_version "10.0")
	(general
		(thickness 1.6)
		(legacy_teardrops no)
	)
	(paper "A4")
	(title_block
		(title "04192023_DAF0TMB3IC0_F0TG_MB_C_brd_V02_OCP.brd")
		(comment 1 "Grand Teton / footprints 5322-5324 of 8354")
	)
	(layers
		(0 "F.Cu" signal "TOP")
		(4 "In1.Cu" signal "GND")
		(6 "In2.Cu" signal "IN1")
		(8 "In3.Cu" signal "GND1")
		(10 "In4.Cu" signal "IN2")
		(12 "In5.Cu" signal "GND2")
		(14 "In6.Cu" signal "IN3")
		(16 "In7.Cu" signal "GND3")
		(18 "In8.Cu" signal "VCC")
		(20 "In9.Cu" signal "VCC1")
		(22 "In10.Cu" signal "GND4")
		(24 "In11.Cu" signal "IN4")
		(26 "In12.Cu" signal "GND5")
		(28 "In13.Cu" signal "IN5")
		(30 "In14.Cu" signal "GND6")
		(32 "In15.Cu" signal "IN6")
		(34 "In16.Cu" signal "GND7")
		(2 "B.Cu" signal "BOTTOM")
		(9 "F.Adhes" user "F.Adhesive")
		(11 "B.Adhes" user "B.Adhesive")
		(13 "F.Paste" user "Package Geometry/Pastemask Top")
		(15 "B.Paste" user "Package Geometry/Pastemask Bottom")
		(5 "F.SilkS" user "Ref Des/Silkscreen Top")
		(7 "B.SilkS" user "Ref Des/Silkscreen Bottom")
		(1 "F.Mask" user "Board Geometry/Soldermask Top")
		(3 "B.Mask" user "Board Geometry/Soldermask Bottom")
		(17 "Dwgs.User" user "User.Drawings")
		(19 "Cmts.User" user "User.Comments")
		(21 "Eco1.User" user "User.Eco1")
		(23 "Eco2.User" user "User.Eco2")
		(25 "Edge.Cuts" user "Board Geometry/Outline")
		(27 "Margin" user)
		(31 "F.CrtYd" user "Package Geometry/Place Bound Top")
		(29 "B.CrtYd" user "Package Geometry/Place Bound Bottom")
		(35 "F.Fab" user "Ref Des/Assembly Top")
		(33 "B.Fab" user "Ref Des/Assembly Bottom")
	)
	(footprint ""
		(layer "B.Cu")
		(at 74.5236 -383.7432 180)
		(property "Reference" "R755"
			(at 0 0 0)
			(layer "B.SilkS")
			(hide yes)
			(effects
				(font
					(size 1.27 1.27)
				)
				(justify mirror)
			)
		)
		(property "Value" ""
			(at 0 0 0)
			(layer "B.Fab")
			(effects
				(font
					(size 1.27 1.27)
				)
				(justify mirror)
			)
		)
		(duplicate_pad_numbers_are_jumpers no)
		(fp_line
			(start 0.32512 0.175006)
			(end 0.32512 -0.175006)
			(stroke
				(width 0.1)
				(type default)
			)
			(layer "B.Fab")
		)
		(fp_line
			(start 0.32512 -0.175006)
			(end -0.32512 -0.175006)
			(stroke
				(width 0.1)
				(type default)
			)
			(layer "B.Fab")
		)
		(fp_line
			(start -0.32512 0.175006)
			(end 0.32512 0.175006)
			(stroke
				(width 0.1)
				(type default)
			)
			(layer "B.Fab")
		)
		(fp_line
			(start -0.32512 -0.175006)
			(end -0.32512 0.175006)
			(stroke
				(width 0.1)
				(type default)
			)
			(layer "B.Fab")
		)
		(pad "1" smd rect
			(at 0.2667 0)
			(size 0.3048 0.381)
			(layers "B.Cu" "B.Mask" "B.Paste")
			(net "P1V8_CPU1_RT_1D")
		)
		(pad "2" smd rect
			(at -0.2667 0 180)
			(size 0.3048 0.381)
			(layers "B.Cu" "B.Mask" "B.Paste")
			(net "RT_CPU1_P1_SCAN_MODE")
		)
	)
	(footprint ""
		(layer "B.Cu")
		(at 181.872382 -20.378166 90)
		(property "Reference" "R2419"
			(at 0 0 90)
			(layer "B.SilkS")
			(hide yes)
			(effects
				(font
					(size 1.27 1.27)
				)
				(justify mirror)
			)
		)
		(property "Value" ""
			(at 0 0 90)
			(layer "B.Fab")
			(effects
				(font
					(size 1.27 1.27)
				)
				(justify mirror)
			)
		)
		(duplicate_pad_numbers_are_jumpers no)
		(fp_line
			(start 0.7874 -0.4064)
			(end -0.7874 -0.4064)
			(stroke
				(width 0.1524)
				(type default)
			)
			(layer "B.SilkS")
		)
		(fp_line
			(start -0.7874 -0.4064)
			(end -0.7874 0.4064)
			(stroke
				(width 0.1524)
				(type default)
			)
			(layer "B.SilkS")
		)
		(fp_line
			(start 0.7874 0.4064)
			(end 0.7874 -0.4064)
			(stroke
				(width 0.1524)
				(type default)
			)
			(layer "B.SilkS")
		)
		(fp_line
			(start -0.7874 0.4064)
			(end 0.7874 0.4064)
			(stroke
				(width 0.1524)
				(type default)
			)
			(layer "B.SilkS")
		)
		(fp_line
			(start 0.67945 -0.305054)
			(end 0.12065 -0.305054)
			(stroke
				(width 0.1)
				(type default)
			)
			(layer "B.Fab")
		)
		(fp_line
			(start 0.12065 -0.305054)
			(end 0.12065 -0.2794)
			(stroke
				(width 0.1)
				(type default)
			)
			(layer "B.Fab")
		)
		(fp_line
			(start -0.12065 -0.3048)
			(end -0.67945 -0.3048)
			(stroke
				(width 0.1)
				(type default)
			)
			(layer "B.Fab")
		)
		(fp_line
			(start -0.67945 -0.3048)
			(end -0.67945 0.3048)
			(stroke
				(width 0.1)
				(type default)
			)
			(layer "B.Fab")
		)
		(fp_line
			(start 0.12065 -0.2794)
			(end -0.12065 -0.2794)
			(stroke
				(width 0.1)
				(type default)
			)
			(layer "B.Fab")
		)
		(fp_line
			(start -0.12065 -0.2794)
			(end -0.12065 -0.3048)
			(stroke
				(width 0.1)
				(type default)
			)
			(layer "B.Fab")
		)
		(fp_line
			(start 0.12065 0.2794)
			(end 0.12065 0.3048)
			(stroke
				(width 0.1)
				(type default)
			)
			(layer "B.Fab")
		)
		(fp_line
			(start -0.120396 0.2794)
			(end 0.12065 0.2794)
			(stroke
				(width 0.1)
				(type default)
			)
			(layer "B.Fab")
		)
		(fp_line
			(start 0.67945 0.3048)
			(end 0.67945 -0.305054)
			(stroke
				(width 0.1)
				(type default)
			)
			(layer "B.Fab")
		)
		(fp_line
			(start 0.12065 0.3048)
			(end 0.67945 0.3048)
			(stroke
				(width 0.1)
				(type default)
			)
			(layer "B.Fab")
		)
		(fp_line
			(start -0.120396 0.3048)
			(end -0.120396 0.2794)
			(stroke
				(width 0.1)
				(type default)
			)
			(layer "B.Fab")
		)
		(fp_line
			(start -0.67945 0.3048)
			(end -0.120396 0.3048)
			(stroke
				(width 0.1)
				(type default)
			)
			(layer "B.Fab")
		)
		(pad "1" smd circle
			(at 0.40005 0 270)
			(size 0 0)
			(layers "B.Cu" "B.Mask" "B.Paste")
			(net "SMB_CPU0_CPU1_APML_SCL")
		)
		(pad "2" smd circle
			(at -0.40005 0 270)
			(size 0 0)
			(layers "B.Cu" "B.Mask" "B.Paste")
			(net "SMB_CPU0_CPU1_APML_SCL_R")
		)
	)
	(footprint ""
		(layer "B.Cu")
		(at 158.90113 -13.127228 180)
		(property "Reference" "R3113"
			(at 0 0 0)
			(layer "B.SilkS")
			(hide yes)
			(effects
				(font
					(size 1.27 1.27)
				)
				(justify mirror)
			)
		)
		(property "Value" ""
			(at 0 0 0)
			(layer "B.Fab")
			(effects
				(font
					(size 1.27 1.27)
				)
				(justify mirror)
			)
		)
		(duplicate_pad_numbers_are_jumpers no)
		(fp_line
			(start 0.7874 0.4064)
			(end 0.7874 -0.4064)
			(stroke
				(width 0.1524)
				(type default)
			)
			(layer "B.SilkS")
		)
		(fp_line
			(start 0.7874 -0.4064)
			(end -0.7874 -0.4064)
			(stroke
				(width 0.1524)
				(type default)
			)
			(layer "B.SilkS")
		)
		(fp_line
			(start -0.7874 0.4064)
			(end 0.7874 0.4064)
			(stroke
				(width 0.1524)
				(type default)
			)
			(layer "B.SilkS")
		)
		(fp_line
			(start -0.7874 -0.4064)
			(end -0.7874 0.4064)
			(stroke
				(width 0.1524)
				(type default)
			)
			(layer "B.SilkS")
		)
		(fp_line
			(start 0.67945 0.3048)
			(end 0.67945 -0.305054)
			(stroke
				(width 0.1)
				(type default)
			)
			(layer "B.Fab")
		)
		(fp_line
			(start 0.67945 -0.305054)
			(end 0.12065 -0.305054)
			(stroke
				(width 0.1)
				(type default)
			)
			(layer "B.Fab")
		)
		(fp_line
			(start 0.12065 0.3048)
			(end 0.67945 0.3048)
			(stroke
				(width 0.1)
				(type default)
			)
			(layer "B.Fab")
		)
		(fp_line
			(start 0.12065 0.2794)
			(end 0.12065 0.3048)
			(stroke
				(width 0.1)
				(type default)
			)
			(layer "B.Fab")
		)
		(fp_line
			(start 0.12065 -0.2794)
			(end -0.12065 -0.2794)
			(stroke
				(width 0.1)
				(type default)
			)
			(layer "B.Fab")
		)
		(fp_line
			(start 0.12065 -0.305054)
			(end 0.12065 -0.2794)
			(stroke
				(width 0.1)
				(type default)
			)
			(layer "B.Fab")
		)
		(fp_line
			(start -0.120396 0.3048)
			(end -0.120396 0.2794)
			(stroke
				(width 0.1)
				(type default)
			)
			(layer "B.Fab")
		)
		(fp_line
			(start -0.120396 0.2794)
			(end 0.12065 0.2794)
			(stroke
				(width 0.1)
				(type default)
			)
			(layer "B.Fab")
		)
		(fp_line
			(start -0.12065 -0.2794)
			(end -0.12065 -0.3048)
			(stroke
				(width 0.1)
				(type default)
			)
			(layer "B.Fab")
		)
		(fp_line
			(start -0.12065 -0.3048)
			(end -0.67945 -0.3048)
			(stroke
				(width 0.1)
				(type default)
			)
			(layer "B.Fab")
		)
		(fp_line
			(start -0.67945 0.3048)
			(end -0.120396 0.3048)
			(stroke
				(width 0.1)
				(type default)
			)
			(layer "B.Fab")
		)
		(fp_line
			(start -0.67945 -0.3048)
			(end -0.67945 0.3048)
			(stroke
				(width 0.1)
				(type default)
			)
			(layer "B.Fab")
		)
		(pad "1" smd circle
			(at 0.40005 0)
			(size 0 0)
			(layers "B.Cu" "B.Mask" "B.Paste")
			(net "SMB_FAN_3V3AUX_SCL")
		)
		(pad "2" smd circle
			(at -0.40005 0)
			(size 0 0)
			(layers "B.Cu" "B.Mask" "B.Paste")
			(net "SMB_FAN_3V3AUX_R_SCL")
		)
	)
)
